Created on Valor NPI 9.6 Update 2 - Netlist Compare Summary.
DATE :  29 Mar 2017
TIME :  13:53:23


     MISMATCH SUMMARY REPORT
     -----------------------

Job  : 16369-sd                Job  : 16369-sd
Step : q                       Step : q
Type : CAD                     Type : CURCAD

-----------------------------------------------

 Mismatch Type: shorted


 Total : 0
-----------------------------------------------

 Mismatch Type: broken


 Total : 0
-----------------------------------------------

 Mismatch Type: missing


 Total : 0
-----------------------------------------------

 Mismatch Type: extra


 Total : 0
-----------------------------------------------
